(kicad_pcb
	(version 20260206)
	(generator "pcbnew")
	(generator_version "10.0")
	(general
		(thickness 1.6)
		(legacy_teardrops no)
	)
	(paper "A4")
	(title_block
		(title "Bryce Canyon_IOM_M2_16342-2_OCP.brd")
		(comment 1 "Bryce Canyon / footprints 110-117 of 1146")
	)
	(layers
		(0 "F.Cu" signal "TOP")
		(4 "In1.Cu" signal "L2GND")
		(6 "In2.Cu" signal "L3")
		(8 "In3.Cu" signal "L4VCC")
		(10 "In4.Cu" signal "L5VCC")
		(12 "In5.Cu" signal "L6")
		(14 "In6.Cu" signal "L7GND")
		(2 "B.Cu" signal "BOTTOM")
		(9 "F.Adhes" user "F.Adhesive")
		(11 "B.Adhes" user "B.Adhesive")
		(13 "F.Paste" user "Package Geometry/Pastemask Top")
		(15 "B.Paste" user "Package Geometry/Pastemask Bottom")
		(5 "F.SilkS" user "Ref Des/Silkscreen Top")
		(7 "B.SilkS" user "Ref Des/Silkscreen Bottom")
		(1 "F.Mask" user "Board Geometry/Soldermask Top")
		(3 "B.Mask" user "Board Geometry/Soldermask Bottom")
		(17 "Dwgs.User" user "User.Drawings")
		(19 "Cmts.User" user "User.Comments")
		(21 "Eco1.User" user "User.Eco1")
		(23 "Eco2.User" user "User.Eco2")
		(25 "Edge.Cuts" user "Board Geometry/Outline")
		(27 "Margin" user)
		(31 "F.CrtYd" user "Package Geometry/Place Bound Top")
		(29 "B.CrtYd" user "Package Geometry/Place Bound Bottom")
		(35 "F.Fab" user "Ref Des/Assembly Top")
		(33 "B.Fab" user "Ref Des/Assembly Bottom")
	)
	(footprint ""
		(layer "F.Cu")
		(at 146.660616 -14.672818 180)
		(property "Reference" "R514"
			(at 0 0 180)
			(layer "F.SilkS")
			(hide yes)
			(effects
				(font
					(size 1.27 1.27)
				)
			)
		)
		(property "Value" "10R3F-GP"
			(at -0.0254 -2.5146 180)
			(unlocked yes)
			(layer "F.Fab")
			(hide yes)
			(effects
				(font
					(size 1.016 1.016)
					(thickness 0.1524)
				)
			)
		)
		(property "Device Type" "R603H22"
			(at -0.0254 -4.0386 180)
			(unlocked yes)
			(layer "F.Fab")
			(hide yes)
			(effects
				(font
					(size 1.016 1.016)
					(thickness 0.1524)
				)
			)
		)
		(duplicate_pad_numbers_are_jumpers no)
		(fp_line
			(start 0.2032 0)
			(end 0.4826 0)
			(stroke
				(width 0.2032)
				(type default)
			)
			(layer "F.SilkS")
		)
		(fp_line
			(start -0.4826 0)
			(end -0.2032 0)
			(stroke
				(width 0.2032)
				(type default)
			)
			(layer "F.SilkS")
		)
		(fp_rect
			(start -0.5842 1.3335)
			(end 0.5842 -1.3335)
			(stroke
				(width 0)
				(type default)
			)
			(fill no)
			(layer "F.CrtYd")
		)
		(fp_rect
			(start -0.5842 1.3335)
			(end 0.5842 -1.3335)
			(stroke
				(width 0)
				(type default)
			)
			(fill no)
			(layer "F.Fab")
		)
		(pad "1" smd custom
			(at 0 -0.762 180)
			(size 0.2159 0.2159)
			(layers "F.Cu" "F.Mask" "F.Paste")
			(net "P1V8_STBY_CC")
			(options
				(clearance outline)
				(anchor circle)
			)
			(primitives
				(gr_poly
					(pts
						(arc
							(start -0.3302 -0.4318)
							(mid -0.402042 -0.402042)
							(end -0.4318 -0.3302)
						)
						(arc
							(start -0.4318 0.3302)
							(mid -0.402042 0.402042)
							(end -0.3302 0.4318)
						)
						(arc
							(start 0.3302 0.4318)
							(mid 0.402042 0.402042)
							(end 0.4318 0.3302)
						)
						(arc
							(start 0.4318 -0.3302)
							(mid 0.402042 -0.402042)
							(end 0.3302 -0.4318)
						)
					)
					(width 0)
					(fill yes)
				)
			)
		)
		(pad "2" smd custom
			(at 0 0.762 180)
			(size 0.2159 0.2159)
			(layers "F.Cu" "F.Mask" "F.Paste")
			(net "P1V8_STBY_CC_R")
			(options
				(clearance outline)
				(anchor circle)
			)
			(primitives
				(gr_poly
					(pts
						(arc
							(start -0.3302 -0.4318)
							(mid -0.402042 -0.402042)
							(end -0.4318 -0.3302)
						)
						(arc
							(start -0.4318 0.3302)
							(mid -0.402042 0.402042)
							(end -0.3302 0.4318)
						)
						(arc
							(start 0.3302 0.4318)
							(mid 0.402042 0.402042)
							(end 0.4318 0.3302)
						)
						(arc
							(start 0.4318 -0.3302)
							(mid 0.402042 -0.402042)
							(end 0.3302 -0.4318)
						)
					)
					(width 0)
					(fill yes)
				)
			)
		)
	)
	(footprint ""
		(layer "F.Cu")
		(at 57.2516 -181.5592)
		(property "Reference" "C169"
			(at 0 0 0)
			(layer "F.SilkS")
			(hide yes)
			(effects
				(font
					(size 1.27 1.27)
				)
			)
		)
		(property "Value" "SCD1U16V2KX-3GP"
			(at 1.1811 -2.7051 0)
			(unlocked yes)
			(layer "F.Fab")
			(hide yes)
			(effects
				(font
					(size 1.016 1.016)
					(thickness 0.1524)
				)
			)
		)
		(property "Device Type" "C402H22"
			(at 1.1811 -4.2291 0)
			(unlocked yes)
			(layer "F.Fab")
			(hide yes)
			(effects
				(font
					(size 1.016 1.016)
					(thickness 0.1524)
				)
			)
		)
		(duplicate_pad_numbers_are_jumpers no)
		(fp_rect
			(start -0.4318 0.9525)
			(end 0.4318 -0.9525)
			(stroke
				(width 0)
				(type default)
			)
			(fill no)
			(layer "F.CrtYd")
		)
		(fp_rect
			(start -0.4318 0.9525)
			(end 0.4318 -0.9525)
			(stroke
				(width 0)
				(type default)
			)
			(fill no)
			(layer "F.Fab")
		)
		(pad "1" smd custom
			(at 0 -0.4445)
			(size 0.1524 0.1524)
			(layers "F.Cu" "F.Mask" "F.Paste")
			(net "P3V3_STBY_OUT")
			(options
				(clearance outline)
				(anchor circle)
			)
			(primitives
				(gr_poly
					(pts
						(arc
							(start 0.3048 -0.2032)
							(mid 0.275042 -0.275042)
							(end 0.2032 -0.3048)
						)
						(arc
							(start -0.2032 -0.3048)
							(mid -0.275042 -0.275042)
							(end -0.3048 -0.2032)
						)
						(arc
							(start -0.3048 0.2032)
							(mid -0.275042 0.275042)
							(end -0.2032 0.3048)
						)
						(arc
							(start 0.2032 0.3048)
							(mid 0.275042 0.275042)
							(end 0.3048 0.2032)
						)
					)
					(width 0)
					(fill yes)
				)
			)
		)
		(pad "2" smd custom
			(at 0 0.4445)
			(size 0.1524 0.1524)
			(layers "F.Cu" "F.Mask" "F.Paste")
			(net "GND")
			(options
				(clearance outline)
				(anchor circle)
			)
			(primitives
				(gr_poly
					(pts
						(arc
							(start 0.3048 -0.2032)
							(mid 0.275042 -0.275042)
							(end 0.2032 -0.3048)
						)
						(arc
							(start -0.2032 -0.3048)
							(mid -0.275042 -0.275042)
							(end -0.3048 -0.2032)
						)
						(arc
							(start -0.3048 0.2032)
							(mid -0.275042 0.275042)
							(end -0.2032 0.3048)
						)
						(arc
							(start 0.2032 0.3048)
							(mid 0.275042 0.275042)
							(end 0.3048 0.2032)
						)
					)
					(width 0)
					(fill yes)
				)
			)
		)
	)
	(footprint ""
		(layer "F.Cu")
		(at 227.069396 -45.95749 180)
		(property "Reference" "C159"
			(at 0 0 180)
			(layer "F.SilkS")
			(hide yes)
			(effects
				(font
					(size 1.27 1.27)
				)
			)
		)
		(property "Value" "SC2200P50V2KX-2GP"
			(at 1.1811 -2.7051 180)
			(unlocked yes)
			(layer "F.Fab")
			(hide yes)
			(effects
				(font
					(size 1.016 1.016)
					(thickness 0.1524)
				)
			)
		)
		(property "Device Type" "C402H22"
			(at 1.1811 -4.2291 180)
			(unlocked yes)
			(layer "F.Fab")
			(hide yes)
			(effects
				(font
					(size 1.016 1.016)
					(thickness 0.1524)
				)
			)
		)
		(duplicate_pad_numbers_are_jumpers no)
		(fp_rect
			(start -0.4318 0.9525)
			(end 0.4318 -0.9525)
			(stroke
				(width 0)
				(type default)
			)
			(fill no)
			(layer "F.CrtYd")
		)
		(fp_rect
			(start -0.4318 0.9525)
			(end 0.4318 -0.9525)
			(stroke
				(width 0)
				(type default)
			)
			(fill no)
			(layer "F.Fab")
		)
		(pad "1" smd custom
			(at 0 -0.4445 180)
			(size 0.1524 0.1524)
			(layers "F.Cu" "F.Mask" "F.Paste")
			(net "P5V_LL")
			(options
				(clearance outline)
				(anchor circle)
			)
			(primitives
				(gr_poly
					(pts
						(arc
							(start 0.3048 -0.2032)
							(mid 0.275042 -0.275042)
							(end 0.2032 -0.3048)
						)
						(arc
							(start -0.2032 -0.3048)
							(mid -0.275042 -0.275042)
							(end -0.3048 -0.2032)
						)
						(arc
							(start -0.3048 0.2032)
							(mid -0.275042 0.275042)
							(end -0.2032 0.3048)
						)
						(arc
							(start 0.2032 0.3048)
							(mid 0.275042 0.275042)
							(end 0.3048 0.2032)
						)
					)
					(width 0)
					(fill yes)
				)
			)
		)
		(pad "2" smd custom
			(at 0 0.4445 180)
			(size 0.1524 0.1524)
			(layers "F.Cu" "F.Mask" "F.Paste")
			(net "P5V_SNB")
			(options
				(clearance outline)
				(anchor circle)
			)
			(primitives
				(gr_poly
					(pts
						(arc
							(start 0.3048 -0.2032)
							(mid 0.275042 -0.275042)
							(end 0.2032 -0.3048)
						)
						(arc
							(start -0.2032 -0.3048)
							(mid -0.275042 -0.275042)
							(end -0.3048 -0.2032)
						)
						(arc
							(start -0.3048 0.2032)
							(mid -0.275042 0.275042)
							(end -0.2032 0.3048)
						)
						(arc
							(start 0.2032 0.3048)
							(mid 0.275042 0.275042)
							(end 0.3048 0.2032)
						)
					)
					(width 0)
					(fill yes)
				)
			)
		)
	)
	(footprint ""
		(layer "F.Cu")
		(at 17.99971 -24.99995)
		(property "Reference" ""
			(at 0 0 0)
			(layer "F.SilkS")
			(hide yes)
			(effects
				(font
					(size 1.27 1.27)
				)
			)
		)
		(property "Value" "*"
			(at -6.38175 0.19685 0)
			(unlocked yes)
			(layer "F.Fab")
			(hide yes)
			(effects
				(font
					(size 1.016 1.016)
					(thickness 0.1524)
				)
			)
		)
		(duplicate_pad_numbers_are_jumpers no)
		(fp_poly
			(pts
				(arc
					(start 5.0673 0)
					(mid -5.0673 0)
					(end 5.0673 0)
				)
			)
			(stroke
				(width 0)
				(type default)
			)
			(fill no)
			(layer "B.CrtYd")
		)
		(fp_poly
			(pts
				(arc
					(start 5.0673 0)
					(mid -5.0673 0)
					(end 5.0673 0)
				)
			)
			(stroke
				(width 0)
				(type default)
			)
			(fill no)
			(layer "F.CrtYd")
		)
		(fp_poly
			(pts
				(arc
					(start 5.0673 0)
					(mid -5.0673 0)
					(end 5.0673 0)
				)
			)
			(stroke
				(width 0)
				(type default)
			)
			(fill no)
			(layer "B.Fab")
		)
		(fp_poly
			(pts
				(arc
					(start 5.0673 0)
					(mid -5.0673 0)
					(end 5.0673 0)
				)
			)
			(stroke
				(width 0)
				(type default)
			)
			(fill no)
			(layer "F.Fab")
		)
		(pad "1" thru_hole circle
			(at 0 0)
			(size 9.525 9.525)
			(drill 3.5052)
			(layers "*.Cu" "*.Mask")
			(remove_unused_layers no)
			(net "Net_36")
			(clearance -2.5019)
			(thermal_gap 0.3048)
			(padstack
				(mode front_inner_back)
				(layer "Inner"
					(shape circle)
					(size 3.9116 3.9116)
					(clearance 0.3048)
				)
				(layer "B.Cu"
					(shape circle)
					(size 9.525 9.525)
					(clearance -2.5019)
				)
			)
		)
	)
	(footprint ""
		(layer "F.Cu")
		(at 41.450006 -169.999914)
		(property "Reference" "NUT1"
			(at 0 0 0)
			(layer "F.SilkS")
			(hide yes)
			(effects
				(font
					(size 1.27 1.27)
				)
			)
		)
		(property "Value" "STF256R168H278-GP"
			(at -4.826 0.0508 0)
			(unlocked yes)
			(layer "F.Fab")
			(hide yes)
			(effects
				(font
					(size 1.016 1.016)
					(thickness 0.1524)
				)
			)
		)
		(property "Device Type" "STF256R168H278"
			(at -4.826 -1.4732 0)
			(unlocked yes)
			(layer "F.Fab")
			(hide yes)
			(effects
				(font
					(size 1.016 1.016)
					(thickness 0.1524)
				)
			)
		)
		(duplicate_pad_numbers_are_jumpers no)
		(fp_circle
			(center 0 0)
			(end 3.6068 0)
			(stroke
				(width 0.3048)
				(type default)
			)
			(fill no)
			(layer "F.SilkS")
		)
		(fp_poly
			(pts
				(arc
					(start 3.7592 0)
					(mid -3.7592 0)
					(end 3.7592 0)
				)
			)
			(stroke
				(width 0)
				(type default)
			)
			(fill no)
			(layer "B.CrtYd")
		)
		(fp_poly
			(pts
				(arc
					(start 2.5019 0)
					(mid -2.5019 0)
					(end 2.5019 0)
				)
			)
			(stroke
				(width 0)
				(type default)
			)
			(fill no)
			(layer "F.CrtYd")
		)
		(fp_poly
			(pts
				(arc
					(start 3.7592 0.00635)
					(mid -3.759205 0)
					(end 3.7592 -0.00635)
				)
				(arc
					(start 2.5019 -0.00635)
					(mid -2.501908 0)
					(end 2.5019 0.00635)
				)
			)
			(stroke
				(width 0)
				(type default)
			)
			(fill no)
			(layer "F.CrtYd")
		)
		(fp_poly
			(pts
				(arc
					(start 3.7592 0)
					(mid -3.7592 0)
					(end 3.7592 0)
				)
			)
			(stroke
				(width 0)
				(type default)
			)
			(fill no)
			(layer "B.Fab")
		)
		(fp_poly
			(pts
				(arc
					(start 3.7592 0)
					(mid -3.7592 0)
					(end 3.7592 0)
				)
			)
			(stroke
				(width 0)
				(type default)
			)
			(fill no)
			(layer "F.Fab")
		)
		(pad "1" thru_hole circle
			(at 0 0)
			(size 6.5024 6.5024)
			(drill 4.2672)
			(layers "*.Cu" "*.Mask")
			(remove_unused_layers no)
			(net "Net_89")
			(clearance -0.6096)
			(thermal_gap 0.3048)
			(padstack
				(mode front_inner_back)
				(layer "Inner"
					(shape circle)
					(size 4.6736 4.6736)
					(clearance 0.3048)
				)
				(layer "B.Cu"
					(shape circle)
					(size 6.5024 6.5024)
					(clearance -0.6096)
				)
			)
		)
	)
	(footprint ""
		(layer "F.Cu")
		(at 91.308174 -123.486164)
		(property "Reference" "R725"
			(at 0 0 0)
			(layer "F.SilkS")
			(hide yes)
			(effects
				(font
					(size 1.27 1.27)
				)
			)
		)
		(property "Value" "4K7R2F-GP"
			(at 0.064008 -3.993896 0)
			(unlocked yes)
			(layer "F.Fab")
			(hide yes)
			(effects
				(font
					(size 1.016 1.016)
					(thickness 0.1524)
				)
			)
		)
		(property "Device Type" "R402H16"
			(at 0.064008 -5.517896 0)
			(unlocked yes)
			(layer "F.Fab")
			(hide yes)
			(effects
				(font
					(size 1.016 1.016)
					(thickness 0.1524)
				)
			)
		)
		(duplicate_pad_numbers_are_jumpers no)
		(fp_line
			(start -0.508 -0.9398)
			(end -0.508 0.9398)
			(stroke
				(width 0.1524)
				(type default)
			)
			(layer "F.SilkS")
		)
		(fp_line
			(start 0.508 -0.9398)
			(end -0.508 -0.9398)
			(stroke
				(width 0.1524)
				(type default)
			)
			(layer "F.SilkS")
		)
		(fp_rect
			(start -0.508 0.9398)
			(end 0.508 -0.9398)
			(stroke
				(width 0)
				(type default)
			)
			(fill no)
			(layer "F.CrtYd")
		)
		(fp_rect
			(start -0.508 0.9398)
			(end 0.508 -0.9398)
			(stroke
				(width 0)
				(type default)
			)
			(fill no)
			(layer "F.Fab")
		)
		(pad "1" smd custom
			(at 0 -0.4445)
			(size 0.1397 0.1397)
			(layers "F.Cu" "F.Mask" "F.Paste")
			(net "P3V3_STBY")
			(options
				(clearance outline)
				(anchor circle)
			)
			(primitives
				(gr_poly
					(pts
						(arc
							(start -0.1778 -0.2794)
							(mid -0.249642 -0.249642)
							(end -0.2794 -0.1778)
						)
						(arc
							(start -0.2794 0.1778)
							(mid -0.249642 0.249642)
							(end -0.1778 0.2794)
						)
						(arc
							(start 0.1778 0.2794)
							(mid 0.249642 0.249642)
							(end 0.2794 0.1778)
						)
						(arc
							(start 0.2794 -0.1778)
							(mid 0.249642 -0.249642)
							(end 0.1778 -0.2794)
						)
					)
					(width 0)
					(fill yes)
				)
			)
		)
		(pad "2" smd custom
			(at 0 0.4445)
			(size 0.1397 0.1397)
			(layers "F.Cu" "F.Mask" "F.Paste")
			(net "UART_COMP_IN_RX")
			(options
				(clearance outline)
				(anchor circle)
			)
			(primitives
				(gr_poly
					(pts
						(arc
							(start -0.1778 -0.2794)
							(mid -0.249642 -0.249642)
							(end -0.2794 -0.1778)
						)
						(arc
							(start -0.2794 0.1778)
							(mid -0.249642 0.249642)
							(end -0.1778 0.2794)
						)
						(arc
							(start 0.1778 0.2794)
							(mid 0.249642 0.249642)
							(end 0.2794 0.1778)
						)
						(arc
							(start 0.2794 -0.1778)
							(mid 0.249642 -0.249642)
							(end 0.1778 -0.2794)
						)
					)
					(width 0)
					(fill yes)
				)
			)
		)
	)
	(footprint ""
		(layer "F.Cu")
		(at 156.729938 -19.661378 90)
		(property "Reference" "C204"
			(at 0 0 90)
			(layer "F.SilkS")
			(hide yes)
			(effects
				(font
					(size 1.27 1.27)
				)
			)
		)
		(property "Value" "SC10U16V5KX-7-GP-U"
			(at -0.0762 -6.1214 90)
			(unlocked yes)
			(layer "F.Fab")
			(hide yes)
			(effects
				(font
					(size 1.016 1.016)
					(thickness 0.1524)
				)
			)
		)
		(property "Device Type" "C805H58"
			(at -0.0762 -8.1534 90)
			(unlocked yes)
			(layer "F.Fab")
			(hide yes)
			(effects
				(font
					(size 1.016 1.016)
					(thickness 0.1524)
				)
			)
		)
		(duplicate_pad_numbers_are_jumpers no)
		(fp_line
			(start 0.635 0)
			(end -0.635 0)
			(stroke
				(width 0.508)
				(type default)
			)
			(layer "F.SilkS")
		)
		(fp_rect
			(start -0.9652 1.778)
			(end 0.9652 -1.778)
			(stroke
				(width 0)
				(type default)
			)
			(fill no)
			(layer "F.CrtYd")
		)
		(fp_poly
			(pts
				(xy -0.9652 -1.778) (xy 0.9652 -1.778) (xy 0.9652 1.778) (xy -0.9652 1.778)
			)
			(stroke
				(width 0)
				(type default)
			)
			(fill no)
			(layer "F.Fab")
		)
		(pad "1" smd rect
			(at 0 -0.9652 90)
			(size 1.397 1.143)
			(layers "F.Cu" "F.Mask" "F.Paste")
			(net "P12V_STBY_VIN_PU4")
		)
		(pad "2" smd rect
			(at 0 0.9652 90)
			(size 1.397 1.143)
			(layers "F.Cu" "F.Mask" "F.Paste")
			(net "GND")
		)
	)
	(footprint ""
		(layer "F.Cu")
		(at 88.773 -127.0508 -90)
		(property "Reference" "R715"
			(at 0 0 270)
			(layer "F.SilkS")
			(hide yes)
			(effects
				(font
					(size 1.27 1.27)
				)
			)
		)
		(property "Value" "0R2J-2-GP"
			(at 0.064008 -3.993896 270)
			(unlocked yes)
			(layer "F.Fab")
			(hide yes)
			(effects
				(font
					(size 1.016 1.016)
					(thickness 0.1524)
				)
			)
		)
		(property "Device Type" "R402H16"
			(at 0.064008 -5.517896 270)
			(unlocked yes)
			(layer "F.Fab")
			(hide yes)
			(effects
				(font
					(size 1.016 1.016)
					(thickness 0.1524)
				)
			)
		)
		(duplicate_pad_numbers_are_jumpers no)
		(fp_line
			(start -0.508 -0.9398)
			(end -0.508 0.9398)
			(stroke
				(width 0.1524)
				(type default)
			)
			(layer "F.SilkS")
		)
		(fp_line
			(start 0.508 -0.9398)
			(end -0.508 -0.9398)
			(stroke
				(width 0.1524)
				(type default)
			)
			(layer "F.SilkS")
		)
		(fp_rect
			(start -0.508 0.9398)
			(end 0.508 -0.9398)
			(stroke
				(width 0)
				(type default)
			)
			(fill no)
			(layer "F.CrtYd")
		)
		(fp_rect
			(start -0.508 0.9398)
			(end 0.508 -0.9398)
			(stroke
				(width 0)
				(type default)
			)
			(fill no)
			(layer "F.Fab")
		)
		(pad "1" smd custom
			(at 0 -0.4445 270)
			(size 0.1397 0.1397)
			(layers "F.Cu" "F.Mask" "F.Paste")
			(net "UART_SEL_MUX")
			(options
				(clearance outline)
				(anchor circle)
			)
			(primitives
				(gr_poly
					(pts
						(arc
							(start -0.1778 -0.2794)
							(mid -0.249642 -0.249642)
							(end -0.2794 -0.1778)
						)
						(arc
							(start -0.2794 0.1778)
							(mid -0.249642 0.249642)
							(end -0.1778 0.2794)
						)
						(arc
							(start 0.1778 0.2794)
							(mid 0.249642 0.249642)
							(end 0.2794 0.1778)
						)
						(arc
							(start 0.2794 -0.1778)
							(mid 0.249642 -0.249642)
							(end 0.1778 -0.2794)
						)
					)
					(width 0)
					(fill yes)
				)
			)
		)
		(pad "2" smd custom
			(at 0 0.4445 270)
			(size 0.1397 0.1397)
			(layers "F.Cu" "F.Mask" "F.Paste")
			(net "BMC_UART_SEL_OUT")
			(options
				(clearance outline)
				(anchor circle)
			)
			(primitives
				(gr_poly
					(pts
						(arc
							(start -0.1778 -0.2794)
							(mid -0.249642 -0.249642)
							(end -0.2794 -0.1778)
						)
						(arc
							(start -0.2794 0.1778)
							(mid -0.249642 0.249642)
							(end -0.1778 0.2794)
						)
						(arc
							(start 0.1778 0.2794)
							(mid 0.249642 0.249642)
							(end 0.2794 0.1778)
						)
						(arc
							(start 0.2794 -0.1778)
							(mid 0.249642 -0.249642)
							(end 0.1778 -0.2794)
						)
					)
					(width 0)
					(fill yes)
				)
			)
		)
	)
)
